(kicad_pcb
	(version 20260206)
	(generator "pcbnew")
	(generator_version "10.0")
	(general
		(thickness 1.6)
		(legacy_teardrops no)
	)
	(paper "A4")
	(title_block
		(title "04192023_DAF0TMB3IC0_F0TG_MB_C_brd_V02_OCP.brd")
		(comment 1 "Grand Teton / footprints 1784-1790 of 8354")
	)
	(layers
		(0 "F.Cu" signal "TOP")
		(4 "In1.Cu" signal "GND")
		(6 "In2.Cu" signal "IN1")
		(8 "In3.Cu" signal "GND1")
		(10 "In4.Cu" signal "IN2")
		(12 "In5.Cu" signal "GND2")
		(14 "In6.Cu" signal "IN3")
		(16 "In7.Cu" signal "GND3")
		(18 "In8.Cu" signal "VCC")
		(20 "In9.Cu" signal "VCC1")
		(22 "In10.Cu" signal "GND4")
		(24 "In11.Cu" signal "IN4")
		(26 "In12.Cu" signal "GND5")
		(28 "In13.Cu" signal "IN5")
		(30 "In14.Cu" signal "GND6")
		(32 "In15.Cu" signal "IN6")
		(34 "In16.Cu" signal "GND7")
		(2 "B.Cu" signal "BOTTOM")
		(9 "F.Adhes" user "F.Adhesive")
		(11 "B.Adhes" user "B.Adhesive")
		(13 "F.Paste" user "Package Geometry/Pastemask Top")
		(15 "B.Paste" user "Package Geometry/Pastemask Bottom")
		(5 "F.SilkS" user "Ref Des/Silkscreen Top")
		(7 "B.SilkS" user "Ref Des/Silkscreen Bottom")
		(1 "F.Mask" user "Board Geometry/Soldermask Top")
		(3 "B.Mask" user "Board Geometry/Soldermask Bottom")
		(17 "Dwgs.User" user "User.Drawings")
		(19 "Cmts.User" user "User.Comments")
		(21 "Eco1.User" user "User.Eco1")
		(23 "Eco2.User" user "User.Eco2")
		(25 "Edge.Cuts" user "Board Geometry/Outline")
		(27 "Margin" user)
		(31 "F.CrtYd" user "Package Geometry/Place Bound Top")
		(29 "B.CrtYd" user "Package Geometry/Place Bound Bottom")
		(35 "F.Fab" user "Ref Des/Assembly Top")
		(33 "B.Fab" user "Ref Des/Assembly Bottom")
	)
	(footprint ""
		(layer "F.Cu")
		(at 303.200308 -40.890698)
		(property "Reference" "R3667"
			(at 0 0 0)
			(layer "F.SilkS")
			(hide yes)
			(effects
				(font
					(size 1.27 1.27)
				)
			)
		)
		(property "Value" ""
			(at 0 0 0)
			(layer "F.Fab")
			(effects
				(font
					(size 1.27 1.27)
				)
			)
		)
		(duplicate_pad_numbers_are_jumpers no)
		(fp_line
			(start -0.7874 -0.4064)
			(end 0.7874 -0.4064)
			(stroke
				(width 0.1524)
				(type default)
			)
			(layer "F.SilkS")
		)
		(fp_line
			(start -0.7874 0.4064)
			(end -0.7874 -0.4064)
			(stroke
				(width 0.1524)
				(type default)
			)
			(layer "F.SilkS")
		)
		(fp_line
			(start 0.7874 -0.4064)
			(end 0.7874 0.4064)
			(stroke
				(width 0.1524)
				(type default)
			)
			(layer "F.SilkS")
		)
		(fp_line
			(start 0.7874 0.4064)
			(end -0.7874 0.4064)
			(stroke
				(width 0.1524)
				(type default)
			)
			(layer "F.SilkS")
		)
		(fp_line
			(start -0.67945 -0.305054)
			(end -0.12065 -0.305054)
			(stroke
				(width 0.1)
				(type default)
			)
			(layer "F.Fab")
		)
		(fp_line
			(start -0.67945 0.3048)
			(end -0.67945 -0.305054)
			(stroke
				(width 0.1)
				(type default)
			)
			(layer "F.Fab")
		)
		(fp_line
			(start -0.12065 -0.305054)
			(end -0.12065 -0.2794)
			(stroke
				(width 0.1)
				(type default)
			)
			(layer "F.Fab")
		)
		(fp_line
			(start -0.12065 -0.2794)
			(end 0.12065 -0.2794)
			(stroke
				(width 0.1)
				(type default)
			)
			(layer "F.Fab")
		)
		(fp_line
			(start -0.12065 0.2794)
			(end -0.12065 0.3048)
			(stroke
				(width 0.1)
				(type default)
			)
			(layer "F.Fab")
		)
		(fp_line
			(start -0.12065 0.3048)
			(end -0.67945 0.3048)
			(stroke
				(width 0.1)
				(type default)
			)
			(layer "F.Fab")
		)
		(fp_line
			(start 0.120396 0.2794)
			(end -0.12065 0.2794)
			(stroke
				(width 0.1)
				(type default)
			)
			(layer "F.Fab")
		)
		(fp_line
			(start 0.120396 0.3048)
			(end 0.120396 0.2794)
			(stroke
				(width 0.1)
				(type default)
			)
			(layer "F.Fab")
		)
		(fp_line
			(start 0.12065 -0.3048)
			(end 0.67945 -0.3048)
			(stroke
				(width 0.1)
				(type default)
			)
			(layer "F.Fab")
		)
		(fp_line
			(start 0.12065 -0.2794)
			(end 0.12065 -0.3048)
			(stroke
				(width 0.1)
				(type default)
			)
			(layer "F.Fab")
		)
		(fp_line
			(start 0.67945 -0.3048)
			(end 0.67945 0.3048)
			(stroke
				(width 0.1)
				(type default)
			)
			(layer "F.Fab")
		)
		(fp_line
			(start 0.67945 0.3048)
			(end 0.120396 0.3048)
			(stroke
				(width 0.1)
				(type default)
			)
			(layer "F.Fab")
		)
		(pad "1" smd circle
			(at -0.40005 0)
			(size 0 0)
			(layers "F.Cu" "F.Mask" "F.Paste")
			(net "P3V3_AUX")
		)
		(pad "2" smd circle
			(at 0.40005 0)
			(size 0 0)
			(layers "F.Cu" "F.Mask" "F.Paste")
			(net "ADC128_A1")
		)
	)
	(footprint ""
		(layer "F.Cu")
		(at 281.94 -426.212 -90)
		(property "Reference" "R4475"
			(at 0 0 270)
			(layer "F.SilkS")
			(hide yes)
			(effects
				(font
					(size 1.27 1.27)
				)
			)
		)
		(property "Value" ""
			(at 0 0 270)
			(layer "F.Fab")
			(effects
				(font
					(size 1.27 1.27)
				)
			)
		)
		(duplicate_pad_numbers_are_jumpers no)
		(fp_line
			(start -1.2954 0.5842)
			(end -1.2954 -0.5842)
			(stroke
				(width 0.1524)
				(type default)
			)
			(layer "F.SilkS")
		)
		(fp_line
			(start 1.2954 0.5842)
			(end -1.2954 0.5842)
			(stroke
				(width 0.1524)
				(type default)
			)
			(layer "F.SilkS")
		)
		(fp_line
			(start -1.2954 -0.5842)
			(end 1.2954 -0.5842)
			(stroke
				(width 0.1524)
				(type default)
			)
			(layer "F.SilkS")
		)
		(fp_line
			(start 1.2954 -0.5842)
			(end 1.2954 0.5842)
			(stroke
				(width 0.1524)
				(type default)
			)
			(layer "F.SilkS")
		)
		(fp_line
			(start -0.8636 0.4572)
			(end -0.8636 0.4318)
			(stroke
				(width 0.1)
				(type default)
			)
			(layer "F.Fab")
		)
		(fp_line
			(start 0.8636 0.4572)
			(end -0.8636 0.4572)
			(stroke
				(width 0.1)
				(type default)
			)
			(layer "F.Fab")
		)
		(fp_line
			(start -0.8636 0.4318)
			(end -0.8636 0.4064)
			(stroke
				(width 0.1)
				(type default)
			)
			(layer "F.Fab")
		)
		(fp_line
			(start -1.1938 0.4064)
			(end -1.1938 -0.406654)
			(stroke
				(width 0.1)
				(type default)
			)
			(layer "F.Fab")
		)
		(fp_line
			(start -0.8636 0.4064)
			(end -1.1938 0.4064)
			(stroke
				(width 0.1)
				(type default)
			)
			(layer "F.Fab")
		)
		(fp_line
			(start 0.8636 0.4064)
			(end 0.8636 0.4572)
			(stroke
				(width 0.1)
				(type default)
			)
			(layer "F.Fab")
		)
		(fp_line
			(start 1.1938 0.4064)
			(end 0.8636 0.4064)
			(stroke
				(width 0.1)
				(type default)
			)
			(layer "F.Fab")
		)
		(fp_line
			(start -1.1938 -0.406654)
			(end -0.8636 -0.406654)
			(stroke
				(width 0.1)
				(type default)
			)
			(layer "F.Fab")
		)
		(fp_line
			(start -0.8636 -0.406654)
			(end -0.8636 -0.4572)
			(stroke
				(width 0.1)
				(type default)
			)
			(layer "F.Fab")
		)
		(fp_line
			(start 0.8636 -0.406654)
			(end 1.1938 -0.406654)
			(stroke
				(width 0.1)
				(type default)
			)
			(layer "F.Fab")
		)
		(fp_line
			(start 1.1938 -0.406654)
			(end 1.1938 0.4064)
			(stroke
				(width 0.1)
				(type default)
			)
			(layer "F.Fab")
		)
		(fp_line
			(start -0.8636 -0.4572)
			(end 0.8636 -0.4572)
			(stroke
				(width 0.1)
				(type default)
			)
			(layer "F.Fab")
		)
		(fp_line
			(start 0.8636 -0.4572)
			(end 0.8636 -0.406654)
			(stroke
				(width 0.1)
				(type default)
			)
			(layer "F.Fab")
		)
		(pad "1" smd rect
			(at -0.7366 0 180)
			(size 0.7112 0.8128)
			(layers "F.Cu" "F.Mask" "F.Paste")
			(net "P3V3_9ZXL045_P0")
		)
		(pad "2" smd rect
			(at 0.7366 0 180)
			(size 0.7112 0.8128)
			(layers "F.Cu" "F.Mask" "F.Paste")
			(net "P3V3_9ZXL045_P0_VDDR")
		)
	)
	(footprint ""
		(layer "F.Cu")
		(at 152.849834 -323.747892 180)
		(property "Reference" "R760"
			(at 0 0 180)
			(layer "F.SilkS")
			(hide yes)
			(effects
				(font
					(size 1.27 1.27)
				)
			)
		)
		(property "Value" ""
			(at 0 0 180)
			(layer "F.Fab")
			(effects
				(font
					(size 1.27 1.27)
				)
			)
		)
		(duplicate_pad_numbers_are_jumpers no)
		(fp_line
			(start 0.7874 0.4064)
			(end -0.7874 0.4064)
			(stroke
				(width 0.1524)
				(type default)
			)
			(layer "F.SilkS")
		)
		(fp_line
			(start 0.7874 -0.4064)
			(end 0.7874 0.4064)
			(stroke
				(width 0.1524)
				(type default)
			)
			(layer "F.SilkS")
		)
		(fp_line
			(start -0.7874 0.4064)
			(end -0.7874 -0.4064)
			(stroke
				(width 0.1524)
				(type default)
			)
			(layer "F.SilkS")
		)
		(fp_line
			(start -0.7874 -0.4064)
			(end 0.7874 -0.4064)
			(stroke
				(width 0.1524)
				(type default)
			)
			(layer "F.SilkS")
		)
		(fp_line
			(start 0.67945 0.3048)
			(end 0.120396 0.3048)
			(stroke
				(width 0.1)
				(type default)
			)
			(layer "F.Fab")
		)
		(fp_line
			(start 0.67945 -0.3048)
			(end 0.67945 0.3048)
			(stroke
				(width 0.1)
				(type default)
			)
			(layer "F.Fab")
		)
		(fp_line
			(start 0.12065 -0.2794)
			(end 0.12065 -0.3048)
			(stroke
				(width 0.1)
				(type default)
			)
			(layer "F.Fab")
		)
		(fp_line
			(start 0.12065 -0.3048)
			(end 0.67945 -0.3048)
			(stroke
				(width 0.1)
				(type default)
			)
			(layer "F.Fab")
		)
		(fp_line
			(start 0.120396 0.3048)
			(end 0.120396 0.2794)
			(stroke
				(width 0.1)
				(type default)
			)
			(layer "F.Fab")
		)
		(fp_line
			(start 0.120396 0.2794)
			(end -0.12065 0.2794)
			(stroke
				(width 0.1)
				(type default)
			)
			(layer "F.Fab")
		)
		(fp_line
			(start -0.12065 0.3048)
			(end -0.67945 0.3048)
			(stroke
				(width 0.1)
				(type default)
			)
			(layer "F.Fab")
		)
		(fp_line
			(start -0.12065 0.2794)
			(end -0.12065 0.3048)
			(stroke
				(width 0.1)
				(type default)
			)
			(layer "F.Fab")
		)
		(fp_line
			(start -0.12065 -0.2794)
			(end 0.12065 -0.2794)
			(stroke
				(width 0.1)
				(type default)
			)
			(layer "F.Fab")
		)
		(fp_line
			(start -0.12065 -0.305054)
			(end -0.12065 -0.2794)
			(stroke
				(width 0.1)
				(type default)
			)
			(layer "F.Fab")
		)
		(fp_line
			(start -0.67945 0.3048)
			(end -0.67945 -0.305054)
			(stroke
				(width 0.1)
				(type default)
			)
			(layer "F.Fab")
		)
		(fp_line
			(start -0.67945 -0.305054)
			(end -0.12065 -0.305054)
			(stroke
				(width 0.1)
				(type default)
			)
			(layer "F.Fab")
		)
		(pad "1" smd circle
			(at -0.40005 0 180)
			(size 0 0)
			(layers "F.Cu" "F.Mask" "F.Paste")
			(net "GND")
		)
		(pad "2" smd circle
			(at 0.40005 0 180)
			(size 0 0)
			(layers "F.Cu" "F.Mask" "F.Paste")
			(net "PD_ESPI_CPU1_CLK2")
		)
	)
	(footprint ""
		(layer "F.Cu")
		(at 112.425988 -256.012442 90)
		(property "Reference" "C2446"
			(at 0 0 90)
			(layer "F.SilkS")
			(hide yes)
			(effects
				(font
					(size 1.27 1.27)
				)
			)
		)
		(property "Value" ""
			(at 0 0 90)
			(layer "F.Fab")
			(effects
				(font
					(size 1.27 1.27)
				)
			)
		)
		(duplicate_pad_numbers_are_jumpers no)
		(fp_line
			(start 0.7874 -0.4064)
			(end 0.7874 0.4064)
			(stroke
				(width 0.1524)
				(type default)
			)
			(layer "F.SilkS")
		)
		(fp_line
			(start -0.7874 -0.4064)
			(end 0.7874 -0.4064)
			(stroke
				(width 0.1524)
				(type default)
			)
			(layer "F.SilkS")
		)
		(fp_line
			(start 0.7874 0.4064)
			(end -0.7874 0.4064)
			(stroke
				(width 0.1524)
				(type default)
			)
			(layer "F.SilkS")
		)
		(fp_line
			(start -0.7874 0.4064)
			(end -0.7874 -0.4064)
			(stroke
				(width 0.1524)
				(type default)
			)
			(layer "F.SilkS")
		)
		(fp_line
			(start -0.12065 -0.305054)
			(end -0.12065 -0.2794)
			(stroke
				(width 0.1)
				(type default)
			)
			(layer "F.Fab")
		)
		(fp_line
			(start -0.67945 -0.305054)
			(end -0.12065 -0.305054)
			(stroke
				(width 0.1)
				(type default)
			)
			(layer "F.Fab")
		)
		(fp_line
			(start 0.67945 -0.3048)
			(end 0.67945 0.3048)
			(stroke
				(width 0.1)
				(type default)
			)
			(layer "F.Fab")
		)
		(fp_line
			(start 0.12065 -0.3048)
			(end 0.67945 -0.3048)
			(stroke
				(width 0.1)
				(type default)
			)
			(layer "F.Fab")
		)
		(fp_line
			(start 0.12065 -0.2794)
			(end 0.12065 -0.3048)
			(stroke
				(width 0.1)
				(type default)
			)
			(layer "F.Fab")
		)
		(fp_line
			(start -0.12065 -0.2794)
			(end 0.12065 -0.2794)
			(stroke
				(width 0.1)
				(type default)
			)
			(layer "F.Fab")
		)
		(fp_line
			(start 0.120396 0.2794)
			(end -0.12065 0.2794)
			(stroke
				(width 0.1)
				(type default)
			)
			(layer "F.Fab")
		)
		(fp_line
			(start -0.12065 0.2794)
			(end -0.12065 0.3048)
			(stroke
				(width 0.1)
				(type default)
			)
			(layer "F.Fab")
		)
		(fp_line
			(start 0.67945 0.3048)
			(end 0.120396 0.3048)
			(stroke
				(width 0.1)
				(type default)
			)
			(layer "F.Fab")
		)
		(fp_line
			(start 0.120396 0.3048)
			(end 0.120396 0.2794)
			(stroke
				(width 0.1)
				(type default)
			)
			(layer "F.Fab")
		)
		(fp_line
			(start -0.12065 0.3048)
			(end -0.67945 0.3048)
			(stroke
				(width 0.1)
				(type default)
			)
			(layer "F.Fab")
		)
		(fp_line
			(start -0.67945 0.3048)
			(end -0.67945 -0.305054)
			(stroke
				(width 0.1)
				(type default)
			)
			(layer "F.Fab")
		)
		(pad "1" smd circle
			(at -0.40005 0 90)
			(size 0 0)
			(layers "F.Cu" "F.Mask" "F.Paste")
			(net "PVDDCR_SOC_P1")
		)
		(pad "2" smd circle
			(at 0.40005 0 90)
			(size 0 0)
			(layers "F.Cu" "F.Mask" "F.Paste")
			(net "GND")
		)
	)
	(footprint ""
		(layer "F.Cu")
		(at 371.681502 -414.636458 -90)
		(property "Reference" "C6565"
			(at 0 0 270)
			(layer "F.SilkS")
			(hide yes)
			(effects
				(font
					(size 1.27 1.27)
				)
			)
		)
		(property "Value" ""
			(at 0 0 270)
			(layer "F.Fab")
			(effects
				(font
					(size 1.27 1.27)
				)
			)
		)
		(duplicate_pad_numbers_are_jumpers no)
		(fp_line
			(start -0.299974 0.150114)
			(end -0.299974 -0.150114)
			(stroke
				(width 0.1)
				(type default)
			)
			(layer "F.Fab")
		)
		(fp_line
			(start 0.299974 0.150114)
			(end -0.299974 0.150114)
			(stroke
				(width 0.1)
				(type default)
			)
			(layer "F.Fab")
		)
		(fp_line
			(start -0.299974 -0.150114)
			(end 0.299974 -0.150114)
			(stroke
				(width 0.1)
				(type default)
			)
			(layer "F.Fab")
		)
		(fp_line
			(start 0.299974 -0.150114)
			(end 0.299974 0.150114)
			(stroke
				(width 0.1)
				(type default)
			)
			(layer "F.Fab")
		)
		(pad "1" smd rect
			(at -0.2667 0 270)
			(size 0.3048 0.381)
			(layers "F.Cu" "F.Mask" "F.Paste")
			(net "P5E_CPU0_P2_TX_BUF_C_DP<0>")
		)
		(pad "2" smd rect
			(at 0.2667 0 270)
			(size 0.3048 0.381)
			(layers "F.Cu" "F.Mask" "F.Paste")
			(net "P5E_CPU0_P2_TX_BUF_DP<0>")
		)
	)
	(footprint ""
		(layer "F.Cu")
		(at 250.55957 -66.238374)
		(property "Reference" "R4064"
			(at 0 0 0)
			(layer "F.SilkS")
			(hide yes)
			(effects
				(font
					(size 1.27 1.27)
				)
			)
		)
		(property "Value" ""
			(at 0 0 0)
			(layer "F.Fab")
			(effects
				(font
					(size 1.27 1.27)
				)
			)
		)
		(duplicate_pad_numbers_are_jumpers no)
		(fp_line
			(start -0.7874 -0.4064)
			(end 0.7874 -0.4064)
			(stroke
				(width 0.1524)
				(type default)
			)
			(layer "F.SilkS")
		)
		(fp_line
			(start -0.7874 0.4064)
			(end -0.7874 -0.4064)
			(stroke
				(width 0.1524)
				(type default)
			)
			(layer "F.SilkS")
		)
		(fp_line
			(start 0.7874 -0.4064)
			(end 0.7874 0.4064)
			(stroke
				(width 0.1524)
				(type default)
			)
			(layer "F.SilkS")
		)
		(fp_line
			(start 0.7874 0.4064)
			(end -0.7874 0.4064)
			(stroke
				(width 0.1524)
				(type default)
			)
			(layer "F.SilkS")
		)
		(fp_line
			(start -0.67945 -0.305054)
			(end -0.12065 -0.305054)
			(stroke
				(width 0.1)
				(type default)
			)
			(layer "F.Fab")
		)
		(fp_line
			(start -0.67945 0.3048)
			(end -0.67945 -0.305054)
			(stroke
				(width 0.1)
				(type default)
			)
			(layer "F.Fab")
		)
		(fp_line
			(start -0.12065 -0.305054)
			(end -0.12065 -0.2794)
			(stroke
				(width 0.1)
				(type default)
			)
			(layer "F.Fab")
		)
		(fp_line
			(start -0.12065 -0.2794)
			(end 0.12065 -0.2794)
			(stroke
				(width 0.1)
				(type default)
			)
			(layer "F.Fab")
		)
		(fp_line
			(start -0.12065 0.2794)
			(end -0.12065 0.3048)
			(stroke
				(width 0.1)
				(type default)
			)
			(layer "F.Fab")
		)
		(fp_line
			(start -0.12065 0.3048)
			(end -0.67945 0.3048)
			(stroke
				(width 0.1)
				(type default)
			)
			(layer "F.Fab")
		)
		(fp_line
			(start 0.120396 0.2794)
			(end -0.12065 0.2794)
			(stroke
				(width 0.1)
				(type default)
			)
			(layer "F.Fab")
		)
		(fp_line
			(start 0.120396 0.3048)
			(end 0.120396 0.2794)
			(stroke
				(width 0.1)
				(type default)
			)
			(layer "F.Fab")
		)
		(fp_line
			(start 0.12065 -0.3048)
			(end 0.67945 -0.3048)
			(stroke
				(width 0.1)
				(type default)
			)
			(layer "F.Fab")
		)
		(fp_line
			(start 0.12065 -0.2794)
			(end 0.12065 -0.3048)
			(stroke
				(width 0.1)
				(type default)
			)
			(layer "F.Fab")
		)
		(fp_line
			(start 0.67945 -0.3048)
			(end 0.67945 0.3048)
			(stroke
				(width 0.1)
				(type default)
			)
			(layer "F.Fab")
		)
		(fp_line
			(start 0.67945 0.3048)
			(end 0.120396 0.3048)
			(stroke
				(width 0.1)
				(type default)
			)
			(layer "F.Fab")
		)
		(pad "1" smd circle
			(at -0.40005 0)
			(size 0 0)
			(layers "F.Cu" "F.Mask" "F.Paste")
			(net "E1S_0_P12V_EN")
		)
		(pad "2" smd circle
			(at 0.40005 0)
			(size 0 0)
			(layers "F.Cu" "F.Mask" "F.Paste")
			(net "P12V_E1S_EN_0_R")
		)
	)
	(footprint ""
		(layer "F.Cu")
		(at 171.196 -109.184948 180)
		(property "Reference" "R167"
			(at 0 0 180)
			(layer "F.SilkS")
			(hide yes)
			(effects
				(font
					(size 1.27 1.27)
				)
			)
		)
		(property "Value" ""
			(at 0 0 180)
			(layer "F.Fab")
			(effects
				(font
					(size 1.27 1.27)
				)
			)
		)
		(duplicate_pad_numbers_are_jumpers no)
		(fp_line
			(start 0.7874 0.4064)
			(end -0.7874 0.4064)
			(stroke
				(width 0.1524)
				(type default)
			)
			(layer "F.SilkS")
		)
		(fp_line
			(start 0.7874 -0.4064)
			(end 0.7874 0.4064)
			(stroke
				(width 0.1524)
				(type default)
			)
			(layer "F.SilkS")
		)
		(fp_line
			(start -0.7874 0.4064)
			(end -0.7874 -0.4064)
			(stroke
				(width 0.1524)
				(type default)
			)
			(layer "F.SilkS")
		)
		(fp_line
			(start -0.7874 -0.4064)
			(end 0.7874 -0.4064)
			(stroke
				(width 0.1524)
				(type default)
			)
			(layer "F.SilkS")
		)
		(fp_line
			(start 0.67945 0.3048)
			(end 0.120396 0.3048)
			(stroke
				(width 0.1)
				(type default)
			)
			(layer "F.Fab")
		)
		(fp_line
			(start 0.67945 -0.3048)
			(end 0.67945 0.3048)
			(stroke
				(width 0.1)
				(type default)
			)
			(layer "F.Fab")
		)
		(fp_line
			(start 0.12065 -0.2794)
			(end 0.12065 -0.3048)
			(stroke
				(width 0.1)
				(type default)
			)
			(layer "F.Fab")
		)
		(fp_line
			(start 0.12065 -0.3048)
			(end 0.67945 -0.3048)
			(stroke
				(width 0.1)
				(type default)
			)
			(layer "F.Fab")
		)
		(fp_line
			(start 0.120396 0.3048)
			(end 0.120396 0.2794)
			(stroke
				(width 0.1)
				(type default)
			)
			(layer "F.Fab")
		)
		(fp_line
			(start 0.120396 0.2794)
			(end -0.12065 0.2794)
			(stroke
				(width 0.1)
				(type default)
			)
			(layer "F.Fab")
		)
		(fp_line
			(start -0.12065 0.3048)
			(end -0.67945 0.3048)
			(stroke
				(width 0.1)
				(type default)
			)
			(layer "F.Fab")
		)
		(fp_line
			(start -0.12065 0.2794)
			(end -0.12065 0.3048)
			(stroke
				(width 0.1)
				(type default)
			)
			(layer "F.Fab")
		)
		(fp_line
			(start -0.12065 -0.2794)
			(end 0.12065 -0.2794)
			(stroke
				(width 0.1)
				(type default)
			)
			(layer "F.Fab")
		)
		(fp_line
			(start -0.12065 -0.305054)
			(end -0.12065 -0.2794)
			(stroke
				(width 0.1)
				(type default)
			)
			(layer "F.Fab")
		)
		(fp_line
			(start -0.67945 0.3048)
			(end -0.67945 -0.305054)
			(stroke
				(width 0.1)
				(type default)
			)
			(layer "F.Fab")
		)
		(fp_line
			(start -0.67945 -0.305054)
			(end -0.12065 -0.305054)
			(stroke
				(width 0.1)
				(type default)
			)
			(layer "F.Fab")
		)
		(pad "1" smd circle
			(at -0.40005 0 180)
			(size 0 0)
			(layers "F.Cu" "F.Mask" "F.Paste")
			(net "SGPIO_SCM_DI_R<0>")
		)
		(pad "2" smd circle
			(at 0.40005 0 180)
			(size 0 0)
			(layers "F.Cu" "F.Mask" "F.Paste")
			(net "SGPIO_SCM_DI_<0>")
		)
	)
)
